(kicad_pcb
	(version 20260206)
	(generator "pcbnew")
	(generator_version "10.0")
	(general
		(thickness 1.6)
		(legacy_teardrops no)
	)
	(paper "A4")
	(title_block
		(title "Wiwynn_Tioga_Pass_MB.brd")
		(comment 1 "Tioga Pass / footprints 1149-1156 of 4770")
	)
	(layers
		(0 "F.Cu" signal "TOP")
		(4 "In1.Cu" signal "L2GND")
		(6 "In2.Cu" signal "L3")
		(8 "In3.Cu" signal "L4GND")
		(10 "In4.Cu" signal "L5")
		(12 "In5.Cu" signal "L6GND")
		(14 "In6.Cu" signal "L7VCC")
		(16 "In7.Cu" signal "L8VCC")
		(18 "In8.Cu" signal "L9GND")
		(20 "In9.Cu" signal "L10")
		(22 "In10.Cu" signal "L11GND")
		(24 "In11.Cu" signal "L12")
		(26 "In12.Cu" signal "L13GND")
		(2 "B.Cu" signal "BOTTOM")
		(9 "F.Adhes" user "F.Adhesive")
		(11 "B.Adhes" user "B.Adhesive")
		(13 "F.Paste" user "Package Geometry/Pastemask Top")
		(15 "B.Paste" user "Package Geometry/Pastemask Bottom")
		(5 "F.SilkS" user "Ref Des/Silkscreen Top")
		(7 "B.SilkS" user "Ref Des/Silkscreen Bottom")
		(1 "F.Mask" user "Board Geometry/Soldermask Top")
		(3 "B.Mask" user "Board Geometry/Soldermask Bottom")
		(17 "Dwgs.User" user "User.Drawings")
		(19 "Cmts.User" user "User.Comments")
		(21 "Eco1.User" user "User.Eco1")
		(23 "Eco2.User" user "User.Eco2")
		(25 "Edge.Cuts" user "Board Geometry/Outline")
		(27 "Margin" user)
		(31 "F.CrtYd" user "Package Geometry/Place Bound Top")
		(29 "B.CrtYd" user "Package Geometry/Place Bound Bottom")
		(35 "F.Fab" user "Ref Des/Assembly Top")
		(33 "B.Fab" user "Ref Des/Assembly Bottom")
	)
	(footprint ""
		(layer "F.Cu")
		(at 476.4786 -41.2369)
		(property "Reference" "C9E9"
			(at 0 0 0)
			(layer "F.SilkS")
			(hide yes)
			(effects
				(font
					(size 1.27 1.27)
				)
			)
		)
		(property "Value" ""
			(at 0 0 0)
			(layer "F.Fab")
			(effects
				(font
					(size 1.27 1.27)
				)
			)
		)
		(duplicate_pad_numbers_are_jumpers no)
		(fp_poly
			(pts
				(xy 0.3048 -0.1016) (xy 0.3048 0.9906) (xy -0.3048 0.9906) (xy -0.3048 -0.1016)
			)
			(stroke
				(width 0)
				(type default)
			)
			(fill no)
			(layer "F.CrtYd")
		)
		(fp_line
			(start -0.3048 -0.1016)
			(end -0.3048 0.9906)
			(stroke
				(width 0.1)
				(type default)
			)
			(layer "F.Fab")
		)
		(fp_line
			(start -0.3048 0.9906)
			(end 0.3048 0.9906)
			(stroke
				(width 0.1)
				(type default)
			)
			(layer "F.Fab")
		)
		(fp_line
			(start 0.3048 -0.1016)
			(end -0.3048 -0.1016)
			(stroke
				(width 0.1)
				(type default)
			)
			(layer "F.Fab")
		)
		(fp_line
			(start 0.3048 0.9906)
			(end 0.3048 -0.1016)
			(stroke
				(width 0.1)
				(type default)
			)
			(layer "F.Fab")
		)
		(pad "1" smd rect
			(at 0 0)
			(size 0.508 0.508)
			(layers "F.Cu" "F.Mask" "F.Paste")
			(net "XTAL_25MHZ_IN")
		)
		(pad "2" smd rect
			(at 0 0.889)
			(size 0.508 0.508)
			(layers "F.Cu" "F.Mask" "F.Paste")
			(net "GND")
		)
		(zone
			(layer "F.Cu")
			(hatch none 0.5)
			(connect_pads
				(clearance 0)
			)
			(min_thickness 0.25)
			(keepout
				(tracks allowed)
				(vias not_allowed)
				(pads allowed)
				(copperpour not_allowed)
				(footprints allowed)
			)
			(placement
				(enabled no)
				(sheetname "")
			)
			(fill
				(thermal_gap 0.5)
				(thermal_bridge_width 0.5)
				(island_removal_mode 0)
			)
			(polygon
				(pts
					(xy 476.2246 -40.9829) (xy 476.7326 -40.9829) (xy 476.7326 -40.6019) (xy 476.2246 -40.6019)
				)
			)
		)
		(zone
			(layer "F.Cu")
			(hatch none 0.5)
			(connect_pads
				(clearance 0)
			)
			(min_thickness 0.25)
			(keepout
				(tracks not_allowed)
				(vias allowed)
				(pads allowed)
				(copperpour not_allowed)
				(footprints allowed)
			)
			(placement
				(enabled no)
				(sheetname "")
			)
			(fill
				(thermal_gap 0.5)
				(thermal_bridge_width 0.5)
				(island_removal_mode 0)
			)
			(polygon
				(pts
					(xy 476.2246 -40.6019) (xy 476.7326 -40.6019) (xy 476.7326 -40.9829) (xy 476.2246 -40.9829)
				)
			)
		)
	)
	(footprint ""
		(layer "F.Cu")
		(at 391.4902 -80.0354 180)
		(property "Reference" "R7D33"
			(at 0 0 180)
			(layer "F.SilkS")
			(hide yes)
			(effects
				(font
					(size 1.27 1.27)
				)
			)
		)
		(property "Value" "*"
			(at 0.064008 -4.108196 180)
			(unlocked yes)
			(layer "F.Fab")
			(hide yes)
			(effects
				(font
					(size 1.27 1.016)
					(thickness 0.1524)
				)
			)
		)
		(property "Device Type" "374R2F-1-GP_SMD-RG-374R2F-1-GPA"
			(at 0.064008 -5.632196 180)
			(unlocked yes)
			(layer "F.Fab")
			(hide yes)
			(effects
				(font
					(size 1.27 1.016)
					(thickness 0.1524)
				)
			)
		)
		(duplicate_pad_numbers_are_jumpers no)
		(fp_line
			(start 0.508 -0.9398)
			(end -0.508 -0.9398)
			(stroke
				(width 0.1524)
				(type default)
			)
			(layer "F.SilkS")
		)
		(fp_line
			(start -0.508 -0.9398)
			(end -0.508 0.9398)
			(stroke
				(width 0.1524)
				(type default)
			)
			(layer "F.SilkS")
		)
		(fp_rect
			(start -0.508 0.9398)
			(end 0.508 -0.9398)
			(stroke
				(width 0)
				(type default)
			)
			(fill no)
			(layer "F.CrtYd")
		)
		(fp_rect
			(start -0.508 0.9398)
			(end 0.508 -0.9398)
			(stroke
				(width 0)
				(type default)
			)
			(fill no)
			(layer "F.Fab")
		)
		(pad "1" smd custom
			(at 0 -0.4445 180)
			(size 0.1397 0.1397)
			(layers "F.Cu" "F.Mask" "F.Paste")
			(net "P3V3")
			(options
				(clearance outline)
				(anchor circle)
			)
			(primitives
				(gr_poly
					(pts
						(arc
							(start -0.1778 -0.2794)
							(mid -0.249642 -0.249642)
							(end -0.2794 -0.1778)
						)
						(arc
							(start -0.2794 0.1778)
							(mid -0.249642 0.249642)
							(end -0.1778 0.2794)
						)
						(arc
							(start 0.1778 0.2794)
							(mid 0.249642 0.249642)
							(end 0.2794 0.1778)
						)
						(arc
							(start 0.2794 -0.1778)
							(mid 0.249642 -0.249642)
							(end 0.1778 -0.2794)
						)
					)
					(width 0)
					(fill yes)
				)
			)
		)
		(pad "2" smd custom
			(at 0 0.4445 180)
			(size 0.1397 0.1397)
			(layers "F.Cu" "F.Mask" "F.Paste")
			(net "P0V7_GTL2104_VREF_0")
			(options
				(clearance outline)
				(anchor circle)
			)
			(primitives
				(gr_poly
					(pts
						(arc
							(start -0.1778 -0.2794)
							(mid -0.249642 -0.249642)
							(end -0.2794 -0.1778)
						)
						(arc
							(start -0.2794 0.1778)
							(mid -0.249642 0.249642)
							(end -0.1778 0.2794)
						)
						(arc
							(start 0.1778 0.2794)
							(mid 0.249642 0.249642)
							(end 0.2794 0.1778)
						)
						(arc
							(start 0.2794 -0.1778)
							(mid 0.249642 -0.249642)
							(end 0.1778 -0.2794)
						)
					)
					(width 0)
					(fill yes)
				)
			)
		)
	)
	(footprint ""
		(layer "F.Cu")
		(at 398.919192 -10.917936)
		(property "Reference" "C7G26"
			(at 0 0 0)
			(layer "F.SilkS")
			(hide yes)
			(effects
				(font
					(size 1.27 1.27)
				)
			)
		)
		(property "Value" ""
			(at 0 0 0)
			(layer "F.Fab")
			(effects
				(font
					(size 1.27 1.27)
				)
			)
		)
		(duplicate_pad_numbers_are_jumpers no)
		(fp_rect
			(start -0.3048 0.9906)
			(end 0.3048 -0.1016)
			(stroke
				(width 0)
				(type default)
			)
			(fill no)
			(layer "F.CrtYd")
		)
		(fp_line
			(start -0.3048 -0.1016)
			(end -0.3048 0.9906)
			(stroke
				(width 0.1)
				(type default)
			)
			(layer "F.Fab")
		)
		(fp_line
			(start -0.3048 0.9906)
			(end 0.3048 0.9906)
			(stroke
				(width 0.1)
				(type default)
			)
			(layer "F.Fab")
		)
		(fp_line
			(start 0.3048 -0.1016)
			(end -0.3048 -0.1016)
			(stroke
				(width 0.1)
				(type default)
			)
			(layer "F.Fab")
		)
		(fp_line
			(start 0.3048 0.9906)
			(end 0.3048 -0.1016)
			(stroke
				(width 0.1)
				(type default)
			)
			(layer "F.Fab")
		)
		(pad "1" smd rect
			(at 0 0)
			(size 0.508 0.508)
			(layers "F.Cu" "F.Mask" "F.Paste")
			(net "P3E_CPU0_PE2_SS_TXN<5>")
		)
		(pad "2" smd rect
			(at 0 0.889)
			(size 0.508 0.508)
			(layers "F.Cu" "F.Mask" "F.Paste")
			(net "P3E_CPU0_PE2_SS_C_TXN<5>")
		)
		(zone
			(layer "F.Cu")
			(hatch none 0.5)
			(connect_pads
				(clearance 0)
			)
			(min_thickness 0.25)
			(keepout
				(tracks allowed)
				(vias not_allowed)
				(pads allowed)
				(copperpour not_allowed)
				(footprints allowed)
			)
			(placement
				(enabled no)
				(sheetname "")
			)
			(fill
				(thermal_gap 0.5)
				(thermal_bridge_width 0.5)
				(island_removal_mode 0)
			)
			(polygon
				(pts
					(xy 398.665192 -10.282936) (xy 399.173192 -10.282936) (xy 399.173192 -10.663936) (xy 398.665192 -10.663936)
				)
			)
		)
		(zone
			(layer "F.Cu")
			(hatch none 0.5)
			(connect_pads
				(clearance 0)
			)
			(min_thickness 0.25)
			(keepout
				(tracks not_allowed)
				(vias allowed)
				(pads allowed)
				(copperpour not_allowed)
				(footprints allowed)
			)
			(placement
				(enabled no)
				(sheetname "")
			)
			(fill
				(thermal_gap 0.5)
				(thermal_bridge_width 0.5)
				(island_removal_mode 0)
			)
			(polygon
				(pts
					(xy 398.665192 -10.282936) (xy 399.173192 -10.282936) (xy 399.173192 -10.663936) (xy 398.665192 -10.663936)
				)
			)
		)
	)
	(footprint ""
		(layer "F.Cu")
		(at 19.6342 -97.310956 180)
		(property "Reference" "C1C10"
			(at 0 0 180)
			(layer "F.SilkS")
			(hide yes)
			(effects
				(font
					(size 1.27 1.27)
				)
			)
		)
		(property "Value" ""
			(at 0 0 180)
			(layer "F.Fab")
			(effects
				(font
					(size 1.27 1.27)
				)
			)
		)
		(duplicate_pad_numbers_are_jumpers no)
		(fp_rect
			(start 0.3048 -0.1016)
			(end -0.3048 0.9906)
			(stroke
				(width 0)
				(type default)
			)
			(fill no)
			(layer "F.CrtYd")
		)
		(fp_line
			(start 0.3048 0.9906)
			(end 0.3048 -0.1016)
			(stroke
				(width 0.1)
				(type default)
			)
			(layer "F.Fab")
		)
		(fp_line
			(start 0.3048 -0.1016)
			(end -0.3048 -0.1016)
			(stroke
				(width 0.1)
				(type default)
			)
			(layer "F.Fab")
		)
		(fp_line
			(start -0.3048 0.9906)
			(end 0.3048 0.9906)
			(stroke
				(width 0.1)
				(type default)
			)
			(layer "F.Fab")
		)
		(fp_line
			(start -0.3048 -0.1016)
			(end -0.3048 0.9906)
			(stroke
				(width 0.1)
				(type default)
			)
			(layer "F.Fab")
		)
		(pad "1" smd rect
			(at 0 0 180)
			(size 0.508 0.508)
			(layers "F.Cu" "F.Mask" "F.Paste")
			(net "A_TSENSE_PVCCIN_CPU1")
		)
		(pad "2" smd rect
			(at 0 0.889 180)
			(size 0.508 0.508)
			(layers "F.Cu" "F.Mask" "F.Paste")
			(net "GND")
		)
		(zone
			(layer "F.Cu")
			(hatch none 0.5)
			(connect_pads
				(clearance 0)
			)
			(min_thickness 0.25)
			(keepout
				(tracks not_allowed)
				(vias allowed)
				(pads allowed)
				(copperpour not_allowed)
				(footprints allowed)
			)
			(placement
				(enabled no)
				(sheetname "")
			)
			(fill
				(thermal_gap 0.5)
				(thermal_bridge_width 0.5)
				(island_removal_mode 0)
			)
			(polygon
				(pts
					(xy 19.3802 -97.564956) (xy 19.8882 -97.564956) (xy 19.8882 -97.945956) (xy 19.3802 -97.945956)
				)
			)
		)
		(zone
			(layer "F.Cu")
			(hatch none 0.5)
			(connect_pads
				(clearance 0)
			)
			(min_thickness 0.25)
			(keepout
				(tracks allowed)
				(vias not_allowed)
				(pads allowed)
				(copperpour not_allowed)
				(footprints allowed)
			)
			(placement
				(enabled no)
				(sheetname "")
			)
			(fill
				(thermal_gap 0.5)
				(thermal_bridge_width 0.5)
				(island_removal_mode 0)
			)
			(polygon
				(pts
					(xy 19.3802 -97.564956) (xy 19.8882 -97.564956) (xy 19.8882 -97.945956) (xy 19.3802 -97.945956)
				)
			)
		)
	)
	(footprint ""
		(layer "F.Cu")
		(at 466.54212 -144.907 -90)
		(property "Reference" "R9A15"
			(at 0 0 270)
			(layer "F.SilkS")
			(hide yes)
			(effects
				(font
					(size 1.27 1.27)
				)
			)
		)
		(property "Value" ""
			(at 0 0 270)
			(layer "F.Fab")
			(effects
				(font
					(size 1.27 1.27)
				)
			)
		)
		(duplicate_pad_numbers_are_jumpers no)
		(fp_poly
			(pts
				(xy -0.2794 -0.1016) (xy 0.2794 -0.1016) (xy 0.2794 0.9906) (xy -0.2794 0.9906)
			)
			(stroke
				(width 0)
				(type default)
			)
			(fill no)
			(layer "F.CrtYd")
		)
		(fp_line
			(start -0.2794 0.9906)
			(end 0.2794 0.9906)
			(stroke
				(width 0.1)
				(type default)
			)
			(layer "F.Fab")
		)
		(fp_line
			(start 0.2794 0.9906)
			(end 0.2794 -0.1016)
			(stroke
				(width 0.1)
				(type default)
			)
			(layer "F.Fab")
		)
		(fp_line
			(start -0.2794 -0.1016)
			(end -0.2794 0.9906)
			(stroke
				(width 0.1)
				(type default)
			)
			(layer "F.Fab")
		)
		(fp_line
			(start 0.2794 -0.1016)
			(end -0.2794 -0.1016)
			(stroke
				(width 0.1)
				(type default)
			)
			(layer "F.Fab")
		)
		(pad "1" smd rect
			(at 0 0 270)
			(size 0.508 0.508)
			(layers "F.Cu" "F.Mask" "F.Paste")
			(net "RST_RSMRST_N")
		)
		(pad "2" smd rect
			(at 0 0.889 270)
			(size 0.508 0.508)
			(layers "F.Cu" "F.Mask" "F.Paste")
			(net "XDP_RSMRST_N")
		)
		(zone
			(layer "F.Cu")
			(hatch none 0.5)
			(connect_pads
				(clearance 0)
			)
			(min_thickness 0.25)
			(keepout
				(tracks not_allowed)
				(vias allowed)
				(pads allowed)
				(copperpour not_allowed)
				(footprints allowed)
			)
			(placement
				(enabled no)
				(sheetname "")
			)
			(fill
				(thermal_gap 0.5)
				(thermal_bridge_width 0.5)
				(island_removal_mode 0)
			)
			(polygon
				(pts
					(xy 465.90712 -145.161) (xy 465.90712 -144.653) (xy 466.28812 -144.653) (xy 466.28812 -145.161)
				)
			)
		)
		(zone
			(layer "F.Cu")
			(hatch none 0.5)
			(connect_pads
				(clearance 0)
			)
			(min_thickness 0.25)
			(keepout
				(tracks allowed)
				(vias not_allowed)
				(pads allowed)
				(copperpour not_allowed)
				(footprints allowed)
			)
			(placement
				(enabled no)
				(sheetname "")
			)
			(fill
				(thermal_gap 0.5)
				(thermal_bridge_width 0.5)
				(island_removal_mode 0)
			)
			(polygon
				(pts
					(xy 466.28812 -145.161) (xy 466.28812 -144.653) (xy 465.90712 -144.653) (xy 465.90712 -145.161)
				)
			)
		)
	)
	(footprint ""
		(layer "F.Cu")
		(at 385.8768 -65.3034)
		(property "Reference" "C7E12"
			(at 0 0 0)
			(layer "F.SilkS")
			(hide yes)
			(effects
				(font
					(size 1.27 1.27)
				)
			)
		)
		(property "Value" "*"
			(at -0.0762 -6.2357 0)
			(unlocked yes)
			(layer "F.Fab")
			(hide yes)
			(effects
				(font
					(size 1.27 1.016)
					(thickness 0.1524)
				)
			)
		)
		(property "Device Type" "SC22U16V5MX-4-GP_SMD-BCG5-SC22A"
			(at -0.0762 -8.2677 0)
			(unlocked yes)
			(layer "F.Fab")
			(hide yes)
			(effects
				(font
					(size 1.27 1.016)
					(thickness 0.1524)
				)
			)
		)
		(duplicate_pad_numbers_are_jumpers no)
		(fp_line
			(start 0.635 0)
			(end -0.635 0)
			(stroke
				(width 0.508)
				(type default)
			)
			(layer "F.SilkS")
		)
		(fp_rect
			(start -0.9652 1.778)
			(end 0.9652 -1.778)
			(stroke
				(width 0)
				(type default)
			)
			(fill no)
			(layer "F.CrtYd")
		)
		(fp_poly
			(pts
				(xy -0.9652 -1.778) (xy 0.9652 -1.778) (xy 0.9652 1.778) (xy -0.9652 1.778)
			)
			(stroke
				(width 0)
				(type default)
			)
			(fill no)
			(layer "F.Fab")
		)
		(pad "1" smd rect
			(at 0 -0.9652)
			(size 1.397 1.143)
			(layers "F.Cu" "F.Mask" "F.Paste")
			(net "VR_FET_SW_P5V_STBY_PVIN")
		)
		(pad "2" smd rect
			(at 0 0.9652)
			(size 1.397 1.143)
			(layers "F.Cu" "F.Mask" "F.Paste")
			(net "GND")
		)
	)
	(footprint ""
		(layer "F.Cu")
		(at 439.626756 -146.477228)
		(property "Reference" "U25W19"
			(at -0.14986 2.621788 0)
			(unlocked yes)
			(layer "F.SilkS")
			(effects
				(font
					(size 1.27 0.964946)
					(thickness 0.000001)
				)
				(justify left)
			)
		)
		(property "Value" ""
			(at 0 0 0)
			(layer "F.Fab")
			(effects
				(font
					(size 1.27 1.27)
				)
			)
		)
		(duplicate_pad_numbers_are_jumpers no)
		(fp_circle
			(center -0.4699 -0.8382)
			(end -0.3429 -0.8382)
			(stroke
				(width 0.254)
				(type default)
			)
			(fill no)
			(layer "F.SilkS")
		)
		(fp_poly
			(pts
				(xy 0.21463 -0.450088) (xy 1.56337 -0.450088) (xy 1.56337 1.75006) (xy 0.21463 1.75006)
			)
			(stroke
				(width 0)
				(type default)
			)
			(fill no)
			(layer "F.CrtYd")
		)
		(fp_line
			(start 0.21463 -0.450088)
			(end 1.56337 -0.450088)
			(stroke
				(width 0.1)
				(type default)
			)
			(layer "F.Fab")
		)
		(fp_line
			(start 0.21463 1.75006)
			(end 0.21463 -0.450088)
			(stroke
				(width 0.1)
				(type default)
			)
			(layer "F.Fab")
		)
		(fp_line
			(start 1.56337 -0.450088)
			(end 1.56337 1.75006)
			(stroke
				(width 0.1)
				(type default)
			)
			(layer "F.Fab")
		)
		(fp_line
			(start 1.56337 1.75006)
			(end 0.21463 1.75006)
			(stroke
				(width 0.1)
				(type default)
			)
			(layer "F.Fab")
		)
		(fp_circle
			(center -0.4699 -0.8382)
			(end -0.3429 -0.8382)
			(stroke
				(width 0.254)
				(type default)
			)
			(fill no)
			(layer "F.Fab")
		)
		(pad "1" smd rect
			(at 0 0)
			(size 1.016 0.381)
			(layers "F.Cu" "F.Mask" "F.Paste")
			(net "BMC_JTAG_SEL_BUF")
		)
		(pad "2" smd rect
			(at 0 0.649986)
			(size 1.016 0.381)
			(layers "F.Cu" "F.Mask" "F.Paste")
			(net "JTAG_BMC_TCK")
		)
		(pad "3" smd rect
			(at 0 1.299972)
			(size 1.016 0.381)
			(layers "F.Cu" "F.Mask" "F.Paste")
			(net "GND")
		)
		(pad "4" smd rect
			(at 1.778 1.299972)
			(size 1.016 0.381)
			(layers "F.Cu" "F.Mask" "F.Paste")
			(net "JTAG_BMC_TCK_BUF")
		)
		(pad "5" smd rect
			(at 1.778 0)
			(size 1.016 0.381)
			(layers "F.Cu" "F.Mask" "F.Paste")
			(net "P3V3_STBY")
		)
	)
	(footprint ""
		(layer "F.Cu")
		(at 16.764 -86.741 180)
		(property "Reference" "R1D8"
			(at 0 0 180)
			(layer "F.SilkS")
			(hide yes)
			(effects
				(font
					(size 1.27 1.27)
				)
			)
		)
		(property "Value" ""
			(at 0 0 180)
			(layer "F.Fab")
			(effects
				(font
					(size 1.27 1.27)
				)
			)
		)
		(duplicate_pad_numbers_are_jumpers no)
		(fp_rect
			(start 0.2794 -0.1016)
			(end -0.2794 0.9906)
			(stroke
				(width 0)
				(type default)
			)
			(fill no)
			(layer "F.CrtYd")
		)
		(fp_line
			(start 0.2794 0.9906)
			(end 0.2794 -0.1016)
			(stroke
				(width 0.1)
				(type default)
			)
			(layer "F.Fab")
		)
		(fp_line
			(start 0.2794 -0.1016)
			(end -0.2794 -0.1016)
			(stroke
				(width 0.1)
				(type default)
			)
			(layer "F.Fab")
		)
		(fp_line
			(start -0.2794 0.9906)
			(end 0.2794 0.9906)
			(stroke
				(width 0.1)
				(type default)
			)
			(layer "F.Fab")
		)
		(fp_line
			(start -0.2794 -0.1016)
			(end -0.2794 0.9906)
			(stroke
				(width 0.1)
				(type default)
			)
			(layer "F.Fab")
		)
		(pad "1" smd rect
			(at 0 0 180)
			(size 0.508 0.508)
			(layers "F.Cu" "F.Mask" "F.Paste")
			(net "P3V3_STBY")
		)
		(pad "2" smd rect
			(at 0 0.889 180)
			(size 0.508 0.508)
			(layers "F.Cu" "F.Mask" "F.Paste")
			(net "PWRGD_PVSA_CPU1_R")
		)
		(zone
			(layer "F.Cu")
			(hatch none 0.5)
			(connect_pads
				(clearance 0)
			)
			(min_thickness 0.25)
			(keepout
				(tracks allowed)
				(vias not_allowed)
				(pads allowed)
				(copperpour not_allowed)
				(footprints allowed)
			)
			(placement
				(enabled no)
				(sheetname "")
			)
			(fill
				(thermal_gap 0.5)
				(thermal_bridge_width 0.5)
				(island_removal_mode 0)
			)
			(polygon
				(pts
					(xy 16.51 -86.995) (xy 17.018 -86.995) (xy 17.018 -87.376) (xy 16.51 -87.376)
				)
			)
		)
		(zone
			(layer "F.Cu")
			(hatch none 0.5)
			(connect_pads
				(clearance 0)
			)
			(min_thickness 0.25)
			(keepout
				(tracks not_allowed)
				(vias allowed)
				(pads allowed)
				(copperpour not_allowed)
				(footprints allowed)
			)
			(placement
				(enabled no)
				(sheetname "")
			)
			(fill
				(thermal_gap 0.5)
				(thermal_bridge_width 0.5)
				(island_removal_mode 0)
			)
			(polygon
				(pts
					(xy 16.51 -86.995) (xy 17.018 -86.995) (xy 17.018 -87.376) (xy 16.51 -87.376)
				)
			)
		)
	)
)
